(kicad_pcb
	(version 20260206)
	(generator "pcbnew")
	(generator_version "10.0")
	(general
		(thickness 1.6)
		(legacy_teardrops no)
	)
	(paper "A4")
	(title_block
		(title "15969-1a.1015WZS0858.brd")
		(comment 1 "Tioga Pass / footprint 37 of 295 (GF2), pads 105-200 of 200")
	)
	(layers
		(0 "F.Cu" signal "TOP")
		(4 "In1.Cu" signal "L2GND")
		(6 "In2.Cu" signal "L3")
		(8 "In3.Cu" signal "L4")
		(10 "In4.Cu" signal "L5GND")
		(2 "B.Cu" signal "BOTTOM")
		(9 "F.Adhes" user "F.Adhesive")
		(11 "B.Adhes" user "B.Adhesive")
		(13 "F.Paste" user "Package Geometry/Pastemask Top")
		(15 "B.Paste" user "Package Geometry/Pastemask Bottom")
		(5 "F.SilkS" user "Ref Des/Silkscreen Top")
		(7 "B.SilkS" user "Ref Des/Silkscreen Bottom")
		(1 "F.Mask" user "Board Geometry/Soldermask Top")
		(3 "B.Mask" user "Board Geometry/Soldermask Bottom")
		(17 "Dwgs.User" user "User.Drawings")
		(19 "Cmts.User" user "User.Comments")
		(21 "Eco1.User" user "User.Eco1")
		(23 "Eco2.User" user "User.Eco2")
		(25 "Edge.Cuts" user "Board Geometry/Outline")
		(27 "Margin" user)
		(31 "F.CrtYd" user "Package Geometry/Place Bound Top")
		(29 "B.CrtYd" user "Package Geometry/Place Bound Bottom")
		(35 "F.Fab" user "Ref Des/Assembly Top")
		(33 "B.Fab" user "Ref Des/Assembly Bottom")
	)
	(footprint ""
		(layer "F.Cu")
		(at 42.3799 13.530072)
		(property "Reference" "GF2"
			(at 0 0 0)
			(layer "F.SilkS")
			(hide yes)
			(effects
				(font
					(size 1.27 1.27)
				)
			)
		)
		(property "Value" "GF-200P-11-GP"
			(at 58.674 -9.3472 0)
			(unlocked yes)
			(layer "F.Fab")
			(hide yes)
			(effects
				(font
					(size 1.016 1.016)
					(thickness 0.1524)
				)
			)
		)
		(property "Device Type" "GF-200P-11"
			(at 58.674 -10.8712 0)
			(unlocked yes)
			(layer "F.Fab")
			(hide yes)
			(effects
				(font
					(size 1.016 1.016)
					(thickness 0.1524)
				)
			)
		)
		(duplicate_pad_numbers_are_jumpers no)
		(pad "105" smd rect
			(at 17.999964 -1.397)
			(size 0.5588 2.794)
			(layers "F.Cu" "F.Mask" "F.Paste")
			(net "P3E_CPU0_PE1_SS_C_TXN<7>")
		)
		(pad "106" smd rect
			(at 17.999964 -1.016)
			(size 0.5588 2.794)
			(drill
				(offset 0 -0.381)
			)
			(layers "F.Cu" "F.Mask" "F.Paste")
			(net "P3E_CPU0_PE1_SS_C_RXP<7>")
		)
		(pad "107" smd rect
			(at 18.800064 -1.397)
			(size 0.5588 2.794)
			(layers "F.Cu" "F.Mask" "F.Paste")
			(net "GND")
		)
		(pad "108" smd rect
			(at 18.800064 -1.016)
			(size 0.5588 2.794)
			(drill
				(offset 0 -0.381)
			)
			(layers "F.Cu" "F.Mask" "F.Paste")
			(net "P3E_CPU0_PE1_SS_C_RXN<7>")
		)
		(pad "109" smd rect
			(at 19.59991 -1.397)
			(size 0.5588 2.794)
			(layers "F.Cu" "F.Mask" "F.Paste")
			(net "P3E_CPU0_PE1_SS_C_TXP<6>")
		)
		(pad "110" smd rect
			(at 19.59991 -1.016)
			(size 0.5588 2.794)
			(drill
				(offset 0 -0.381)
			)
			(layers "F.Cu" "F.Mask" "F.Paste")
			(net "GND")
		)
		(pad "111" smd rect
			(at 20.40001 -1.397)
			(size 0.5588 2.794)
			(layers "F.Cu" "F.Mask" "F.Paste")
			(net "P3E_CPU0_PE1_SS_C_TXN<6>")
		)
		(pad "112" smd rect
			(at 20.40001 -1.016)
			(size 0.5588 2.794)
			(drill
				(offset 0 -0.381)
			)
			(layers "F.Cu" "F.Mask" "F.Paste")
			(net "P3E_CPU0_PE1_SS_C_RXP<6>")
		)
		(pad "113" smd rect
			(at 21.20011 -1.397)
			(size 0.5588 2.794)
			(layers "F.Cu" "F.Mask" "F.Paste")
			(net "GND")
		)
		(pad "114" smd rect
			(at 21.20011 -1.016)
			(size 0.5588 2.794)
			(drill
				(offset 0 -0.381)
			)
			(layers "F.Cu" "F.Mask" "F.Paste")
			(net "P3E_CPU0_PE1_SS_C_RXN<6>")
		)
		(pad "115" smd rect
			(at 21.999956 -1.397)
			(size 0.5588 2.794)
			(layers "F.Cu" "F.Mask" "F.Paste")
			(net "P3E_CPU0_PE1_SS_C_TXP<5>")
		)
		(pad "116" smd rect
			(at 21.999956 -1.016)
			(size 0.5588 2.794)
			(drill
				(offset 0 -0.381)
			)
			(layers "F.Cu" "F.Mask" "F.Paste")
			(net "GND")
		)
		(pad "117" smd rect
			(at 22.800056 -1.397)
			(size 0.5588 2.794)
			(layers "F.Cu" "F.Mask" "F.Paste")
			(net "P3E_CPU0_PE1_SS_C_TXN<5>")
		)
		(pad "118" smd rect
			(at 22.800056 -1.016)
			(size 0.5588 2.794)
			(drill
				(offset 0 -0.381)
			)
			(layers "F.Cu" "F.Mask" "F.Paste")
			(net "P3E_CPU0_PE1_SS_C_RXP<5>")
		)
		(pad "119" smd rect
			(at 23.599902 -1.397)
			(size 0.5588 2.794)
			(layers "F.Cu" "F.Mask" "F.Paste")
			(net "GND")
		)
		(pad "120" smd rect
			(at 23.599902 -1.016)
			(size 0.5588 2.794)
			(drill
				(offset 0 -0.381)
			)
			(layers "F.Cu" "F.Mask" "F.Paste")
			(net "P3E_CPU0_PE1_SS_C_RXN<5>")
		)
		(pad "121" smd rect
			(at 24.400002 -1.397)
			(size 0.5588 2.794)
			(layers "F.Cu" "F.Mask" "F.Paste")
			(net "P3E_CPU0_PE1_SS_C_TXP<4>")
		)
		(pad "122" smd rect
			(at 24.400002 -1.016)
			(size 0.5588 2.794)
			(drill
				(offset 0 -0.381)
			)
			(layers "F.Cu" "F.Mask" "F.Paste")
			(net "GND")
		)
		(pad "123" smd rect
			(at 25.200102 -1.397)
			(size 0.5588 2.794)
			(layers "F.Cu" "F.Mask" "F.Paste")
			(net "P3E_CPU0_PE1_SS_C_TXN<4>")
		)
		(pad "124" smd rect
			(at 25.200102 -1.016)
			(size 0.5588 2.794)
			(drill
				(offset 0 -0.381)
			)
			(layers "F.Cu" "F.Mask" "F.Paste")
			(net "P3E_CPU0_PE1_SS_C_RXP<4>")
		)
		(pad "125" smd rect
			(at 25.999948 -1.397)
			(size 0.5588 2.794)
			(layers "F.Cu" "F.Mask" "F.Paste")
			(net "GND")
		)
		(pad "126" smd rect
			(at 25.999948 -1.016)
			(size 0.5588 2.794)
			(drill
				(offset 0 -0.381)
			)
			(layers "F.Cu" "F.Mask" "F.Paste")
			(net "P3E_CPU0_PE1_SS_C_RXN<4>")
		)
		(pad "127" smd rect
			(at 26.800048 -1.397)
			(size 0.5588 2.794)
			(layers "F.Cu" "F.Mask" "F.Paste")
			(net "P3E_CPU0_PE1_SS_C_TXP<3>")
		)
		(pad "128" smd rect
			(at 26.800048 -1.016)
			(size 0.5588 2.794)
			(drill
				(offset 0 -0.381)
			)
			(layers "F.Cu" "F.Mask" "F.Paste")
			(net "GND")
		)
		(pad "129" smd rect
			(at 27.599894 -1.397)
			(size 0.5588 2.794)
			(layers "F.Cu" "F.Mask" "F.Paste")
			(net "P3E_CPU0_PE1_SS_C_TXN<3>")
		)
		(pad "130" smd rect
			(at 27.599894 -1.016)
			(size 0.5588 2.794)
			(drill
				(offset 0 -0.381)
			)
			(layers "F.Cu" "F.Mask" "F.Paste")
			(net "P3E_CPU0_PE1_SS_C_RXP<3>")
		)
		(pad "131" smd rect
			(at 28.399994 -1.397)
			(size 0.5588 2.794)
			(layers "F.Cu" "F.Mask" "F.Paste")
			(net "GND")
		)
		(pad "132" smd rect
			(at 28.399994 -1.016)
			(size 0.5588 2.794)
			(drill
				(offset 0 -0.381)
			)
			(layers "F.Cu" "F.Mask" "F.Paste")
			(net "P3E_CPU0_PE1_SS_C_RXN<3>")
		)
		(pad "133" smd rect
			(at 29.200094 -1.397)
			(size 0.5588 2.794)
			(layers "F.Cu" "F.Mask" "F.Paste")
			(net "P3E_CPU0_PE1_SS_C_TXP<2>")
		)
		(pad "134" smd rect
			(at 29.200094 -1.016)
			(size 0.5588 2.794)
			(drill
				(offset 0 -0.381)
			)
			(layers "F.Cu" "F.Mask" "F.Paste")
			(net "GND")
		)
		(pad "135" smd rect
			(at 29.99994 -1.397)
			(size 0.5588 2.794)
			(layers "F.Cu" "F.Mask" "F.Paste")
			(net "P3E_CPU0_PE1_SS_C_TXN<2>")
		)
		(pad "136" smd rect
			(at 29.99994 -1.016)
			(size 0.5588 2.794)
			(drill
				(offset 0 -0.381)
			)
			(layers "F.Cu" "F.Mask" "F.Paste")
			(net "P3E_CPU0_PE1_SS_C_RXP<2>")
		)
		(pad "137" smd rect
			(at 30.80004 -1.397)
			(size 0.5588 2.794)
			(layers "F.Cu" "F.Mask" "F.Paste")
			(net "GND")
		)
		(pad "138" smd rect
			(at 30.80004 -1.016)
			(size 0.5588 2.794)
			(drill
				(offset 0 -0.381)
			)
			(layers "F.Cu" "F.Mask" "F.Paste")
			(net "P3E_CPU0_PE1_SS_C_RXN<2>")
		)
		(pad "139" smd rect
			(at 31.599886 -1.397)
			(size 0.5588 2.794)
			(layers "F.Cu" "F.Mask" "F.Paste")
			(net "P3E_CPU0_PE1_SS_C_TXP<1>")
		)
		(pad "140" smd rect
			(at 31.599886 -1.016)
			(size 0.5588 2.794)
			(drill
				(offset 0 -0.381)
			)
			(layers "F.Cu" "F.Mask" "F.Paste")
			(net "GND")
		)
		(pad "141" smd rect
			(at 32.399986 -1.397)
			(size 0.5588 2.794)
			(layers "F.Cu" "F.Mask" "F.Paste")
			(net "P3E_CPU0_PE1_SS_C_TXN<1>")
		)
		(pad "142" smd rect
			(at 32.399986 -1.016)
			(size 0.5588 2.794)
			(drill
				(offset 0 -0.381)
			)
			(layers "F.Cu" "F.Mask" "F.Paste")
			(net "P3E_CPU0_PE1_SS_C_RXP<1>")
		)
		(pad "143" smd rect
			(at 33.200086 -1.397)
			(size 0.5588 2.794)
			(layers "F.Cu" "F.Mask" "F.Paste")
			(net "GND")
		)
		(pad "144" smd rect
			(at 33.200086 -1.016)
			(size 0.5588 2.794)
			(drill
				(offset 0 -0.381)
			)
			(layers "F.Cu" "F.Mask" "F.Paste")
			(net "P3E_CPU0_PE1_SS_C_RXN<1>")
		)
		(pad "145" smd rect
			(at 33.999932 -1.397)
			(size 0.5588 2.794)
			(layers "F.Cu" "F.Mask" "F.Paste")
			(net "P3E_CPU0_PE1_SS_C_TXP<0>")
		)
		(pad "146" smd rect
			(at 33.999932 -1.016)
			(size 0.5588 2.794)
			(drill
				(offset 0 -0.381)
			)
			(layers "F.Cu" "F.Mask" "F.Paste")
			(net "GND")
		)
		(pad "147" smd rect
			(at 34.800032 -1.397)
			(size 0.5588 2.794)
			(layers "F.Cu" "F.Mask" "F.Paste")
			(net "P3E_CPU0_PE1_SS_C_TXN<0>")
		)
		(pad "148" smd rect
			(at 34.800032 -1.016)
			(size 0.5588 2.794)
			(drill
				(offset 0 -0.381)
			)
			(layers "F.Cu" "F.Mask" "F.Paste")
			(net "P3E_CPU0_PE1_SS_C_RXP<0>")
		)
		(pad "149" smd rect
			(at 35.599878 -1.397)
			(size 0.5588 2.794)
			(layers "F.Cu" "F.Mask" "F.Paste")
			(net "GND")
		)
		(pad "150" smd rect
			(at 35.599878 -1.016)
			(size 0.5588 2.794)
			(drill
				(offset 0 -0.381)
			)
			(layers "F.Cu" "F.Mask" "F.Paste")
			(net "P3E_CPU0_PE1_SS_C_RXN<0>")
		)
		(pad "151" smd rect
			(at 36.399978 -1.397)
			(size 0.5588 2.794)
			(layers "F.Cu" "F.Mask" "F.Paste")
			(net "P3E_CPU0_PE2_SS_C_TXP<0>")
		)
		(pad "152" smd rect
			(at 36.399978 -1.016)
			(size 0.5588 2.794)
			(drill
				(offset 0 -0.381)
			)
			(layers "F.Cu" "F.Mask" "F.Paste")
			(net "GND")
		)
		(pad "153" smd rect
			(at 37.200078 -1.397)
			(size 0.5588 2.794)
			(layers "F.Cu" "F.Mask" "F.Paste")
			(net "P3E_CPU0_PE2_SS_C_TXN<0>")
		)
		(pad "154" smd rect
			(at 37.200078 -1.016)
			(size 0.5588 2.794)
			(drill
				(offset 0 -0.381)
			)
			(layers "F.Cu" "F.Mask" "F.Paste")
			(net "P3E_CPU0_PE2_SS_RXP<0>")
		)
		(pad "155" smd rect
			(at 37.999924 -1.397)
			(size 0.5588 2.794)
			(layers "F.Cu" "F.Mask" "F.Paste")
			(net "GND")
		)
		(pad "156" smd rect
			(at 37.999924 -1.016)
			(size 0.5588 2.794)
			(drill
				(offset 0 -0.381)
			)
			(layers "F.Cu" "F.Mask" "F.Paste")
			(net "P3E_CPU0_PE2_SS_RXN<0>")
		)
		(pad "157" smd rect
			(at 38.800024 -1.397)
			(size 0.5588 2.794)
			(layers "F.Cu" "F.Mask" "F.Paste")
			(net "P3E_CPU0_PE2_SS_C_TXP<1>")
		)
		(pad "158" smd rect
			(at 38.800024 -1.016)
			(size 0.5588 2.794)
			(drill
				(offset 0 -0.381)
			)
			(layers "F.Cu" "F.Mask" "F.Paste")
			(net "GND")
		)
		(pad "159" smd rect
			(at 39.600124 -1.397)
			(size 0.5588 2.794)
			(layers "F.Cu" "F.Mask" "F.Paste")
			(net "P3E_CPU0_PE2_SS_C_TXN<1>")
		)
		(pad "160" smd rect
			(at 39.600124 -1.016)
			(size 0.5588 2.794)
			(drill
				(offset 0 -0.381)
			)
			(layers "F.Cu" "F.Mask" "F.Paste")
			(net "P3E_CPU0_PE2_SS_RXP<1>")
		)
		(pad "161" smd rect
			(at 40.39997 -1.397)
			(size 0.5588 2.794)
			(layers "F.Cu" "F.Mask" "F.Paste")
			(net "GND")
		)
		(pad "162" smd rect
			(at 40.39997 -1.016)
			(size 0.5588 2.794)
			(drill
				(offset 0 -0.381)
			)
			(layers "F.Cu" "F.Mask" "F.Paste")
			(net "P3E_CPU0_PE2_SS_RXN<1>")
		)
		(pad "163" smd rect
			(at 41.20007 -1.397)
			(size 0.5588 2.794)
			(layers "F.Cu" "F.Mask" "F.Paste")
			(net "P3E_CPU0_PE2_SS_C_TXP<2>")
		)
		(pad "164" smd rect
			(at 41.20007 -1.016)
			(size 0.5588 2.794)
			(drill
				(offset 0 -0.381)
			)
			(layers "F.Cu" "F.Mask" "F.Paste")
			(net "GND")
		)
		(pad "165" smd rect
			(at 41.999916 -1.397)
			(size 0.5588 2.794)
			(layers "F.Cu" "F.Mask" "F.Paste")
			(net "P3E_CPU0_PE2_SS_C_TXN<2>")
		)
		(pad "166" smd rect
			(at 41.999916 -1.016)
			(size 0.5588 2.794)
			(drill
				(offset 0 -0.381)
			)
			(layers "F.Cu" "F.Mask" "F.Paste")
			(net "P3E_CPU0_PE2_SS_RXP<2>")
		)
		(pad "167" smd rect
			(at 42.800016 -1.397)
			(size 0.5588 2.794)
			(layers "F.Cu" "F.Mask" "F.Paste")
			(net "GND")
		)
		(pad "168" smd rect
			(at 42.800016 -1.016)
			(size 0.5588 2.794)
			(drill
				(offset 0 -0.381)
			)
			(layers "F.Cu" "F.Mask" "F.Paste")
			(net "P3E_CPU0_PE2_SS_RXN<2>")
		)
		(pad "169" smd rect
			(at 43.600116 -1.397)
			(size 0.5588 2.794)
			(layers "F.Cu" "F.Mask" "F.Paste")
			(net "P3E_CPU0_PE2_SS_C_TXP<3>")
		)
		(pad "170" smd rect
			(at 43.600116 -1.016)
			(size 0.5588 2.794)
			(drill
				(offset 0 -0.381)
			)
			(layers "F.Cu" "F.Mask" "F.Paste")
			(net "GND")
		)
		(pad "171" smd rect
			(at 44.399962 -1.397)
			(size 0.5588 2.794)
			(layers "F.Cu" "F.Mask" "F.Paste")
			(net "P3E_CPU0_PE2_SS_C_TXN<3>")
		)
		(pad "172" smd rect
			(at 44.399962 -1.016)
			(size 0.5588 2.794)
			(drill
				(offset 0 -0.381)
			)
			(layers "F.Cu" "F.Mask" "F.Paste")
			(net "P3E_CPU0_PE2_SS_RXP<3>")
		)
		(pad "173" smd rect
			(at 45.200062 -1.397)
			(size 0.5588 2.794)
			(layers "F.Cu" "F.Mask" "F.Paste")
			(net "GND")
		)
		(pad "174" smd rect
			(at 45.200062 -1.016)
			(size 0.5588 2.794)
			(drill
				(offset 0 -0.381)
			)
			(layers "F.Cu" "F.Mask" "F.Paste")
			(net "P3E_CPU0_PE2_SS_RXN<3>")
		)
		(pad "175" smd rect
			(at 45.999908 -1.397)
			(size 0.5588 2.794)
			(layers "F.Cu" "F.Mask" "F.Paste")
			(net "P3E_CPU0_PE2_SS_C_TXP<4>")
		)
		(pad "176" smd rect
			(at 45.999908 -1.016)
			(size 0.5588 2.794)
			(drill
				(offset 0 -0.381)
			)
			(layers "F.Cu" "F.Mask" "F.Paste")
			(net "GND")
		)
		(pad "177" smd rect
			(at 46.800008 -1.397)
			(size 0.5588 2.794)
			(layers "F.Cu" "F.Mask" "F.Paste")
			(net "P3E_CPU0_PE2_SS_C_TXN<4>")
		)
		(pad "178" smd rect
			(at 46.800008 -1.016)
			(size 0.5588 2.794)
			(drill
				(offset 0 -0.381)
			)
			(layers "F.Cu" "F.Mask" "F.Paste")
			(net "P3E_CPU0_PE2_SS_RXP<4>")
		)
		(pad "179" smd rect
			(at 47.600108 -1.397)
			(size 0.5588 2.794)
			(layers "F.Cu" "F.Mask" "F.Paste")
			(net "GND")
		)
		(pad "180" smd rect
			(at 47.600108 -1.016)
			(size 0.5588 2.794)
			(drill
				(offset 0 -0.381)
			)
			(layers "F.Cu" "F.Mask" "F.Paste")
			(net "P3E_CPU0_PE2_SS_RXN<4>")
		)
		(pad "181" smd rect
			(at 48.399954 -1.397)
			(size 0.5588 2.794)
			(layers "F.Cu" "F.Mask" "F.Paste")
			(net "P3E_CPU0_PE2_SS_C_TXP<5>")
		)
		(pad "182" smd rect
			(at 48.399954 -1.016)
			(size 0.5588 2.794)
			(drill
				(offset 0 -0.381)
			)
			(layers "F.Cu" "F.Mask" "F.Paste")
			(net "GND")
		)
		(pad "183" smd rect
			(at 49.200054 -1.397)
			(size 0.5588 2.794)
			(layers "F.Cu" "F.Mask" "F.Paste")
			(net "P3E_CPU0_PE2_SS_C_TXN<5>")
		)
		(pad "184" smd rect
			(at 49.200054 -1.016)
			(size 0.5588 2.794)
			(drill
				(offset 0 -0.381)
			)
			(layers "F.Cu" "F.Mask" "F.Paste")
			(net "P3E_CPU0_PE2_SS_RXP<5>")
		)
		(pad "185" smd rect
			(at 49.9999 -1.397)
			(size 0.5588 2.794)
			(layers "F.Cu" "F.Mask" "F.Paste")
			(net "GND")
		)
		(pad "186" smd rect
			(at 49.9999 -1.016)
			(size 0.5588 2.794)
			(drill
				(offset 0 -0.381)
			)
			(layers "F.Cu" "F.Mask" "F.Paste")
			(net "P3E_CPU0_PE2_SS_RXN<5>")
		)
		(pad "187" smd rect
			(at 50.8 -1.397)
			(size 0.5588 2.794)
			(layers "F.Cu" "F.Mask" "F.Paste")
			(net "P3E_CPU0_PE2_SS_C_TXP<6>")
		)
		(pad "188" smd rect
			(at 50.8 -1.016)
			(size 0.5588 2.794)
			(drill
				(offset 0 -0.381)
			)
			(layers "F.Cu" "F.Mask" "F.Paste")
			(net "GND")
		)
		(pad "189" smd rect
			(at 51.6001 -1.397)
			(size 0.5588 2.794)
			(layers "F.Cu" "F.Mask" "F.Paste")
			(net "P3E_CPU0_PE2_SS_C_TXN<6>")
		)
		(pad "190" smd rect
			(at 51.6001 -1.016)
			(size 0.5588 2.794)
			(drill
				(offset 0 -0.381)
			)
			(layers "F.Cu" "F.Mask" "F.Paste")
			(net "P3E_CPU0_PE2_SS_RXP<6>")
		)
		(pad "191" smd rect
			(at 52.399946 -1.397)
			(size 0.5588 2.794)
			(layers "F.Cu" "F.Mask" "F.Paste")
			(net "GND")
		)
		(pad "192" smd rect
			(at 52.399946 -1.016)
			(size 0.5588 2.794)
			(drill
				(offset 0 -0.381)
			)
			(layers "F.Cu" "F.Mask" "F.Paste")
			(net "P3E_CPU0_PE2_SS_RXN<6>")
		)
		(pad "193" smd rect
			(at 53.200046 -1.397)
			(size 0.5588 2.794)
			(layers "F.Cu" "F.Mask" "F.Paste")
			(net "P3E_CPU0_PE2_SS_C_TXP<7>")
		)
		(pad "194" smd rect
			(at 53.200046 -1.016)
			(size 0.5588 2.794)
			(drill
				(offset 0 -0.381)
			)
			(layers "F.Cu" "F.Mask" "F.Paste")
			(net "GND")
		)
		(pad "195" smd rect
			(at 53.999892 -1.397)
			(size 0.5588 2.794)
			(layers "F.Cu" "F.Mask" "F.Paste")
			(net "P3E_CPU0_PE2_SS_C_TXN<7>")
		)
		(pad "196" smd rect
			(at 53.999892 -1.016)
			(size 0.5588 2.794)
			(drill
				(offset 0 -0.381)
			)
			(layers "F.Cu" "F.Mask" "F.Paste")
			(net "P3E_CPU0_PE2_SS_RXP<7>")
		)
		(pad "197" smd rect
			(at 54.799992 -1.397)
			(size 0.5588 2.794)
			(layers "F.Cu" "F.Mask" "F.Paste")
			(net "GND")
		)
		(pad "198" smd rect
			(at 54.799992 -1.016)
			(size 0.5588 2.794)
			(drill
				(offset 0 -0.381)
			)
			(layers "F.Cu" "F.Mask" "F.Paste")
			(net "P3E_CPU0_PE2_SS_RXN<7>")
		)
		(pad "199" smd rect
			(at 55.600092 -1.397)
			(size 0.5588 2.794)
			(layers "F.Cu" "F.Mask" "F.Paste")
			(net "FM_PRSNT_2_6_N")
		)
		(pad "200" smd rect
			(at 55.600092 -1.016)
			(size 0.5588 2.794)
			(drill
				(offset 0 -0.381)
			)
			(layers "F.Cu" "F.Mask" "F.Paste")
			(net "GND")
		)
	)
)
